# T6G (Grand Teton) — schematic netlist excerpt (pin names and nets, part order shuffled) for the footprints in the layout excerpt that follows; sources: Cadence DE-HDL packaged netlist, KiCad conversion of 04192023_DAF0TMB3IC0_F0TG_MB_C_brd_V02_OCP.brd

L16  Q_INDUCTOR  BLM18PG300SN1D IND  pkg SMLF  page 257 : \1\ = P3V3_AUX ; \2\ = P3V3_ADC128_VCC
PC136  Q_CAP  0.1UF 25V 10% X7R  pkg 0402  page 192 : A = PVDD_33_S5 ; B = GND

(kicad_pcb
	(version 20260206)
	(generator "pcbnew")
	(generator_version "10.0")
	(general
		(thickness 1.6)
		(legacy_teardrops no)
	)
	(paper "A4")
	(title_block
		(title "04192023_DAF0TMB3IC0_F0TG_MB_C_brd_V02_OCP.brd")
		(comment 1 "Grand Teton / footprints 4024-4025 of 8354")
	)
	(layers
		(0 "F.Cu" signal "TOP")
		(4 "In1.Cu" signal "GND")
		(6 "In2.Cu" signal "IN1")
		(8 "In3.Cu" signal "GND1")
		(10 "In4.Cu" signal "IN2")
		(12 "In5.Cu" signal "GND2")
		(14 "In6.Cu" signal "IN3")
		(16 "In7.Cu" signal "GND3")
		(18 "In8.Cu" signal "VCC")
		(20 "In9.Cu" signal "VCC1")
		(22 "In10.Cu" signal "GND4")
		(24 "In11.Cu" signal "IN4")
		(26 "In12.Cu" signal "GND5")
		(28 "In13.Cu" signal "IN5")
		(30 "In14.Cu" signal "GND6")
		(32 "In15.Cu" signal "IN6")
		(34 "In16.Cu" signal "GND7")
		(2 "B.Cu" signal "BOTTOM")
		(9 "F.Adhes" user "F.Adhesive")
		(11 "B.Adhes" user "B.Adhesive")
		(13 "F.Paste" user "Package Geometry/Pastemask Top")
		(15 "B.Paste" user "Package Geometry/Pastemask Bottom")
		(5 "F.SilkS" user "Ref Des/Silkscreen Top")
		(7 "B.SilkS" user "Ref Des/Silkscreen Bottom")
		(1 "F.Mask" user "Board Geometry/Soldermask Top")
		(3 "B.Mask" user "Board Geometry/Soldermask Bottom")
		(17 "Dwgs.User" user "User.Drawings")
		(19 "Cmts.User" user "User.Comments")
		(21 "Eco1.User" user "User.Eco1")
		(23 "Eco2.User" user "User.Eco2")
		(25 "Edge.Cuts" user "Board Geometry/Outline")
		(27 "Margin" user)
		(31 "F.CrtYd" user "Package Geometry/Place Bound Top")
		(29 "B.CrtYd" user "Package Geometry/Place Bound Bottom")
		(35 "F.Fab" user "Ref Des/Assembly Top")
		(33 "B.Fab" user "Ref Des/Assembly Bottom")
	)
	(footprint ""
		(layer "F.Cu")
		(at 205.147926 -331.016864 90)
		(property "Reference" "PC136"
			(at 0 0 90)
			(layer "F.SilkS")
			(hide yes)
			(effects
				(font
					(size 1.27 1.27)
				)
			)
		)
		(property "Value" ""
			(at 0 0 90)
			(layer "F.Fab")
			(effects
				(font
					(size 1.27 1.27)
				)
			)
		)
		(duplicate_pad_numbers_are_jumpers no)
		(fp_line
			(start 0.7874 -0.4064)
			(end 0.7874 0.4064)
			(stroke
				(width 0.1524)
				(type default)
			)
			(layer "F.SilkS")
		)
		(fp_line
			(start -0.7874 -0.4064)
			(end 0.7874 -0.4064)
			(stroke
				(width 0.1524)
				(type default)
			)
			(layer "F.SilkS")
		)
		(fp_line
			(start 0.7874 0.4064)
			(end -0.7874 0.4064)
			(stroke
				(width 0.1524)
				(type default)
			)
			(layer "F.SilkS")
		)
		(fp_line
			(start -0.7874 0.4064)
			(end -0.7874 -0.4064)
			(stroke
				(width 0.1524)
				(type default)
			)
			(layer "F.SilkS")
		)
		(fp_line
			(start -0.12065 -0.305054)
			(end -0.12065 -0.2794)
			(stroke
				(width 0.1)
				(type default)
			)
			(layer "F.Fab")
		)
		(fp_line
			(start -0.67945 -0.305054)
			(end -0.12065 -0.305054)
			(stroke
				(width 0.1)
				(type default)
			)
			(layer "F.Fab")
		)
		(fp_line
			(start 0.67945 -0.3048)
			(end 0.67945 0.3048)
			(stroke
				(width 0.1)
				(type default)
			)
			(layer "F.Fab")
		)
		(fp_line
			(start 0.12065 -0.3048)
			(end 0.67945 -0.3048)
			(stroke
				(width 0.1)
				(type default)
			)
			(layer "F.Fab")
		)
		(fp_line
			(start 0.12065 -0.2794)
			(end 0.12065 -0.3048)
			(stroke
				(width 0.1)
				(type default)
			)
			(layer "F.Fab")
		)
		(fp_line
			(start -0.12065 -0.2794)
			(end 0.12065 -0.2794)
			(stroke
				(width 0.1)
				(type default)
			)
			(layer "F.Fab")
		)
		(fp_line
			(start 0.120396 0.2794)
			(end -0.12065 0.2794)
			(stroke
				(width 0.1)
				(type default)
			)
			(layer "F.Fab")
		)
		(fp_line
			(start -0.12065 0.2794)
			(end -0.12065 0.3048)
			(stroke
				(width 0.1)
				(type default)
			)
			(layer "F.Fab")
		)
		(fp_line
			(start 0.67945 0.3048)
			(end 0.120396 0.3048)
			(stroke
				(width 0.1)
				(type default)
			)
			(layer "F.Fab")
		)
		(fp_line
			(start 0.120396 0.3048)
			(end 0.120396 0.2794)
			(stroke
				(width 0.1)
				(type default)
			)
			(layer "F.Fab")
		)
		(fp_line
			(start -0.12065 0.3048)
			(end -0.67945 0.3048)
			(stroke
				(width 0.1)
				(type default)
			)
			(layer "F.Fab")
		)
		(fp_line
			(start -0.67945 0.3048)
			(end -0.67945 -0.305054)
			(stroke
				(width 0.1)
				(type default)
			)
			(layer "F.Fab")
		)
		(pad "1" smd circle
			(at -0.40005 0 90)
			(size 0 0)
			(layers "F.Cu" "F.Mask" "F.Paste")
			(net "PVDD_33_S5")
		)
		(pad "2" smd circle
			(at 0.40005 0 90)
			(size 0 0)
			(layers "F.Cu" "F.Mask" "F.Paste")
			(net "GND")
		)
	)
	(footprint ""
		(layer "F.Cu")
		(at 303.023778 -46.444154)
		(property "Reference" "L16"
			(at 0 0 0)
			(layer "F.SilkS")
			(hide yes)
			(effects
				(font
					(size 1.27 1.27)
				)
			)
		)
		(property "Value" ""
			(at 0 0 0)
			(layer "F.Fab")
			(effects
				(font
					(size 1.27 1.27)
				)
			)
		)
		(duplicate_pad_numbers_are_jumpers no)
		(fp_line
			(start -1.27 -0.5842)
			(end 1.27 -0.5842)
			(stroke
				(width 0.1524)
				(type default)
			)
			(layer "F.SilkS")
		)
		(fp_line
			(start -1.27 -0.5588)
			(end -1.27 -0.5842)
			(stroke
				(width 0.1524)
				(type default)
			)
			(layer "F.SilkS")
		)
		(fp_line
			(start -1.27 0.5842)
			(end -1.27 -0.5842)
			(stroke
				(width 0.1524)
				(type default)
			)
			(layer "F.SilkS")
		)
		(fp_line
			(start 1.27 0.5842)
			(end -1.27 0.5842)
			(stroke
				(width 0.1524)
				(type default)
			)
			(layer "F.SilkS")
		)
		(fp_line
			(start 1.27 0.5842)
			(end 1.27 -0.5842)
			(stroke
				(width 0.1524)
				(type default)
			)
			(layer "F.SilkS")
		)
		(fp_line
			(start -1.194308 -0.406654)
			(end -0.9144 -0.406654)
			(stroke
				(width 0.1)
				(type default)
			)
			(layer "F.Fab")
		)
		(fp_line
			(start -1.194308 0.406654)
			(end -1.194308 -0.406654)
			(stroke
				(width 0.1)
				(type default)
			)
			(layer "F.Fab")
		)
		(fp_line
			(start -0.9144 -0.508)
			(end 0.9144 -0.508)
			(stroke
				(width 0.1)
				(type default)
			)
			(layer "F.Fab")
		)
		(fp_line
			(start -0.9144 -0.406654)
			(end -0.9144 -0.508)
			(stroke
				(width 0.1)
				(type default)
			)
			(layer "F.Fab")
		)
		(fp_line
			(start -0.9144 0.406654)
			(end -1.194308 0.406654)
			(stroke
				(width 0.1)
				(type default)
			)
			(layer "F.Fab")
		)
		(fp_line
			(start -0.9144 0.508)
			(end -0.9144 0.406654)
			(stroke
				(width 0.1)
				(type default)
			)
			(layer "F.Fab")
		)
		(fp_line
			(start 0.9144 -0.508)
			(end 0.9144 -0.406654)
			(stroke
				(width 0.1)
				(type default)
			)
			(layer "F.Fab")
		)
		(fp_line
			(start 0.9144 -0.406654)
			(end 1.1938 -0.406654)
			(stroke
				(width 0.1)
				(type default)
			)
			(layer "F.Fab")
		)
		(fp_line
			(start 0.9144 0.4064)
			(end 0.9144 0.508)
			(stroke
				(width 0.1)
				(type default)
			)
			(layer "F.Fab")
		)
		(fp_line
			(start 0.9144 0.508)
			(end -0.9144 0.508)
			(stroke
				(width 0.1)
				(type default)
			)
			(layer "F.Fab")
		)
		(fp_line
			(start 1.1938 -0.406654)
			(end 1.1938 0.4064)
			(stroke
				(width 0.1)
				(type default)
			)
			(layer "F.Fab")
		)
		(fp_line
			(start 1.1938 0.4064)
			(end 0.9144 0.4064)
			(stroke
				(width 0.1)
				(type default)
			)
			(layer "F.Fab")
		)
		(pad "1" smd rect
			(at -0.7366 0 270)
			(size 0.7112 0.8128)
			(layers "F.Cu" "F.Mask" "F.Paste")
			(net "P3V3_AUX")
		)
		(pad "2" smd rect
			(at 0.7366 0 270)
			(size 0.7112 0.8128)
			(layers "F.Cu" "F.Mask" "F.Paste")
			(net "P3V3_ADC128_VCC")
		)
	)
)
